(kicad_pcb
	(version 20260206)
	(generator "pcbnew")
	(generator_version "10.0")
	(general
		(thickness 1.6)
		(legacy_teardrops no)
	)
	(paper "A4")
	(title_block
		(title "Bryce Canyon_F.DPB_16315-1-OCP.brd")
		(comment 1 "Bryce Canyon / footprints 1101-1108 of 2223")
	)
	(layers
		(0 "F.Cu" signal "TOP")
		(4 "In1.Cu" signal "L2GND")
		(6 "In2.Cu" signal "L3")
		(8 "In3.Cu" signal "L4GND")
		(10 "In4.Cu" signal "L5")
		(12 "In5.Cu" signal "L6VCC")
		(14 "In6.Cu" signal "L7VCC")
		(16 "In7.Cu" signal "L8")
		(18 "In8.Cu" signal "L9GND")
		(20 "In9.Cu" signal "L10")
		(22 "In10.Cu" signal "L11GND")
		(2 "B.Cu" signal "BOTTOM")
		(9 "F.Adhes" user "F.Adhesive")
		(11 "B.Adhes" user "B.Adhesive")
		(13 "F.Paste" user "Package Geometry/Pastemask Top")
		(15 "B.Paste" user "Package Geometry/Pastemask Bottom")
		(5 "F.SilkS" user "Ref Des/Silkscreen Top")
		(7 "B.SilkS" user "Ref Des/Silkscreen Bottom")
		(1 "F.Mask" user "Board Geometry/Soldermask Top")
		(3 "B.Mask" user "Board Geometry/Soldermask Bottom")
		(17 "Dwgs.User" user "User.Drawings")
		(19 "Cmts.User" user "User.Comments")
		(21 "Eco1.User" user "User.Eco1")
		(23 "Eco2.User" user "User.Eco2")
		(25 "Edge.Cuts" user "Board Geometry/Outline")
		(27 "Margin" user)
		(31 "F.CrtYd" user "Package Geometry/Place Bound Top")
		(29 "B.CrtYd" user "Package Geometry/Place Bound Bottom")
		(35 "F.Fab" user "Ref Des/Assembly Top")
		(33 "B.Fab" user "Ref Des/Assembly Bottom")
	)
	(footprint ""
		(layer "F.Cu")
		(at 180.7464 -278.554942 90)
		(property "Reference" "R258"
			(at 0 0 90)
			(layer "F.SilkS")
			(hide yes)
			(effects
				(font
					(size 1.27 1.27)
				)
			)
		)
		(property "Value" "4K7R2J-2-GP"
			(at 0.064008 -3.993896 90)
			(unlocked yes)
			(layer "F.Fab")
			(hide yes)
			(effects
				(font
					(size 1.016 1.016)
					(thickness 0.1524)
				)
			)
		)
		(property "Device Type" "R402H16"
			(at 0.064008 -5.517896 90)
			(unlocked yes)
			(layer "F.Fab")
			(hide yes)
			(effects
				(font
					(size 1.016 1.016)
					(thickness 0.1524)
				)
			)
		)
		(duplicate_pad_numbers_are_jumpers no)
		(fp_line
			(start 0.508 -0.9398)
			(end -0.508 -0.9398)
			(stroke
				(width 0.1524)
				(type default)
			)
			(layer "F.SilkS")
		)
		(fp_line
			(start -0.508 -0.9398)
			(end -0.508 0.9398)
			(stroke
				(width 0.1524)
				(type default)
			)
			(layer "F.SilkS")
		)
		(fp_rect
			(start -0.508 0.9398)
			(end 0.508 -0.9398)
			(stroke
				(width 0)
				(type default)
			)
			(fill no)
			(layer "F.CrtYd")
		)
		(fp_rect
			(start -0.508 0.9398)
			(end 0.508 -0.9398)
			(stroke
				(width 0)
				(type default)
			)
			(fill no)
			(layer "F.Fab")
		)
		(pad "1" smd custom
			(at 0 -0.4445 90)
			(size 0.1397 0.1397)
			(layers "F.Cu" "F.Mask" "F.Paste")
			(net "SW_PWR_R_HDD5")
			(options
				(clearance outline)
				(anchor circle)
			)
			(primitives
				(gr_poly
					(pts
						(arc
							(start -0.1778 -0.2794)
							(mid -0.249642 -0.249642)
							(end -0.2794 -0.1778)
						)
						(arc
							(start -0.2794 0.1778)
							(mid -0.249642 0.249642)
							(end -0.1778 0.2794)
						)
						(arc
							(start 0.1778 0.2794)
							(mid 0.249642 0.249642)
							(end 0.2794 0.1778)
						)
						(arc
							(start 0.2794 -0.1778)
							(mid 0.249642 -0.249642)
							(end 0.1778 -0.2794)
						)
					)
					(width 0)
					(fill yes)
				)
			)
		)
		(pad "2" smd custom
			(at 0 0.4445 90)
			(size 0.1397 0.1397)
			(layers "F.Cu" "F.Mask" "F.Paste")
			(net "GND")
			(options
				(clearance outline)
				(anchor circle)
			)
			(primitives
				(gr_poly
					(pts
						(arc
							(start -0.1778 -0.2794)
							(mid -0.249642 -0.249642)
							(end -0.2794 -0.1778)
						)
						(arc
							(start -0.2794 0.1778)
							(mid -0.249642 0.249642)
							(end -0.1778 0.2794)
						)
						(arc
							(start 0.1778 0.2794)
							(mid 0.249642 0.249642)
							(end 0.2794 0.1778)
						)
						(arc
							(start 0.2794 -0.1778)
							(mid 0.249642 -0.249642)
							(end 0.1778 -0.2794)
						)
					)
					(width 0)
					(fill yes)
				)
			)
		)
	)
	(footprint ""
		(layer "F.Cu")
		(at 111.473996 -53.126894 -90)
		(property "Reference" "C399"
			(at 0 0 270)
			(layer "F.SilkS")
			(hide yes)
			(effects
				(font
					(size 1.27 1.27)
				)
			)
		)
		(property "Value" "SCD033U25V2KX-GP"
			(at 1.1811 -2.7051 270)
			(unlocked yes)
			(layer "F.Fab")
			(hide yes)
			(effects
				(font
					(size 1.016 1.016)
					(thickness 0.1524)
				)
			)
		)
		(property "Device Type" "C402H22"
			(at 1.1811 -4.2291 270)
			(unlocked yes)
			(layer "F.Fab")
			(hide yes)
			(effects
				(font
					(size 1.016 1.016)
					(thickness 0.1524)
				)
			)
		)
		(duplicate_pad_numbers_are_jumpers no)
		(fp_rect
			(start -0.4318 0.9525)
			(end 0.4318 -0.9525)
			(stroke
				(width 0)
				(type default)
			)
			(fill no)
			(layer "F.CrtYd")
		)
		(fp_rect
			(start -0.4318 0.9525)
			(end 0.4318 -0.9525)
			(stroke
				(width 0)
				(type default)
			)
			(fill no)
			(layer "F.Fab")
		)
		(pad "1" smd custom
			(at 0 -0.4445 270)
			(size 0.1524 0.1524)
			(layers "F.Cu" "F.Mask" "F.Paste")
			(net "SW_HDD_P27")
			(options
				(clearance outline)
				(anchor circle)
			)
			(primitives
				(gr_poly
					(pts
						(arc
							(start 0.3048 -0.2032)
							(mid 0.275042 -0.275042)
							(end 0.2032 -0.3048)
						)
						(arc
							(start -0.2032 -0.3048)
							(mid -0.275042 -0.275042)
							(end -0.3048 -0.2032)
						)
						(arc
							(start -0.3048 0.2032)
							(mid -0.275042 0.275042)
							(end -0.2032 0.3048)
						)
						(arc
							(start 0.2032 0.3048)
							(mid 0.275042 0.275042)
							(end 0.3048 0.2032)
						)
					)
					(width 0)
					(fill yes)
				)
			)
		)
		(pad "2" smd custom
			(at 0 0.4445 270)
			(size 0.1524 0.1524)
			(layers "F.Cu" "F.Mask" "F.Paste")
			(net "GND")
			(options
				(clearance outline)
				(anchor circle)
			)
			(primitives
				(gr_poly
					(pts
						(arc
							(start 0.3048 -0.2032)
							(mid 0.275042 -0.275042)
							(end 0.2032 -0.3048)
						)
						(arc
							(start -0.2032 -0.3048)
							(mid -0.275042 -0.275042)
							(end -0.3048 -0.2032)
						)
						(arc
							(start -0.3048 0.2032)
							(mid -0.275042 0.275042)
							(end -0.2032 0.3048)
						)
						(arc
							(start 0.2032 0.3048)
							(mid 0.275042 0.275042)
							(end 0.3048 0.2032)
						)
					)
					(width 0)
					(fill yes)
				)
			)
		)
	)
	(footprint ""
		(layer "F.Cu")
		(at 35.797998 -292.169342 -90)
		(property "Reference" "R958"
			(at 0 0 270)
			(layer "F.SilkS")
			(hide yes)
			(effects
				(font
					(size 1.27 1.27)
				)
			)
		)
		(property "Value" "10KR2F-2-GP"
			(at 0.064008 -3.993896 270)
			(unlocked yes)
			(layer "F.Fab")
			(hide yes)
			(effects
				(font
					(size 1.016 1.016)
					(thickness 0.1524)
				)
			)
		)
		(property "Device Type" "R402H16"
			(at 0.064008 -5.517896 270)
			(unlocked yes)
			(layer "F.Fab")
			(hide yes)
			(effects
				(font
					(size 1.016 1.016)
					(thickness 0.1524)
				)
			)
		)
		(duplicate_pad_numbers_are_jumpers no)
		(fp_line
			(start -0.508 -0.9398)
			(end -0.508 0.9398)
			(stroke
				(width 0.1524)
				(type default)
			)
			(layer "F.SilkS")
		)
		(fp_line
			(start 0.508 -0.9398)
			(end -0.508 -0.9398)
			(stroke
				(width 0.1524)
				(type default)
			)
			(layer "F.SilkS")
		)
		(fp_rect
			(start -0.508 0.9398)
			(end 0.508 -0.9398)
			(stroke
				(width 0)
				(type default)
			)
			(fill no)
			(layer "F.CrtYd")
		)
		(fp_rect
			(start -0.508 0.9398)
			(end 0.508 -0.9398)
			(stroke
				(width 0)
				(type default)
			)
			(fill no)
			(layer "F.Fab")
		)
		(pad "1" smd custom
			(at 0 -0.4445 270)
			(size 0.1397 0.1397)
			(layers "F.Cu" "F.Mask" "F.Paste")
			(net "P3V3_STBY_A")
			(options
				(clearance outline)
				(anchor circle)
			)
			(primitives
				(gr_poly
					(pts
						(arc
							(start -0.1778 -0.2794)
							(mid -0.249642 -0.249642)
							(end -0.2794 -0.1778)
						)
						(arc
							(start -0.2794 0.1778)
							(mid -0.249642 0.249642)
							(end -0.1778 0.2794)
						)
						(arc
							(start 0.1778 0.2794)
							(mid 0.249642 0.249642)
							(end 0.2794 0.1778)
						)
						(arc
							(start 0.2794 -0.1778)
							(mid 0.249642 -0.249642)
							(end 0.1778 -0.2794)
						)
					)
					(width 0)
					(fill yes)
				)
			)
		)
		(pad "2" smd custom
			(at 0 0.4445 270)
			(size 0.1397 0.1397)
			(layers "F.Cu" "F.Mask" "F.Paste")
			(net "HDD_PRSNT_0")
			(options
				(clearance outline)
				(anchor circle)
			)
			(primitives
				(gr_poly
					(pts
						(arc
							(start -0.1778 -0.2794)
							(mid -0.249642 -0.249642)
							(end -0.2794 -0.1778)
						)
						(arc
							(start -0.2794 0.1778)
							(mid -0.249642 0.249642)
							(end -0.1778 0.2794)
						)
						(arc
							(start 0.1778 0.2794)
							(mid 0.249642 0.249642)
							(end 0.2794 0.1778)
						)
						(arc
							(start 0.2794 -0.1778)
							(mid 0.249642 -0.249642)
							(end 0.1778 -0.2794)
						)
					)
					(width 0)
					(fill yes)
				)
			)
		)
	)
	(footprint ""
		(layer "F.Cu")
		(at 426.120052 -291.127942 -90)
		(property "Reference" "R336"
			(at 0 0 270)
			(layer "F.SilkS")
			(hide yes)
			(effects
				(font
					(size 1.27 1.27)
				)
			)
		)
		(property "Value" "2R6F-GP"
			(at -0.0508 -4.8514 270)
			(unlocked yes)
			(layer "F.Fab")
			(hide yes)
			(effects
				(font
					(size 1.016 1.016)
					(thickness 0.1524)
				)
			)
		)
		(property "Device Type" "R1206H26"
			(at 0 -6.3754 270)
			(unlocked yes)
			(layer "F.Fab")
			(hide yes)
			(effects
				(font
					(size 1.016 1.016)
					(thickness 0.1524)
				)
			)
		)
		(duplicate_pad_numbers_are_jumpers no)
		(fp_line
			(start -1.016 2.2352)
			(end -1.016 -2.2352)
			(stroke
				(width 0.1524)
				(type default)
			)
			(layer "F.SilkS")
		)
		(fp_line
			(start 1.016 2.2352)
			(end -1.016 2.2352)
			(stroke
				(width 0.1524)
				(type default)
			)
			(layer "F.SilkS")
		)
		(fp_line
			(start -1.016 -2.2352)
			(end 1.016 -2.2352)
			(stroke
				(width 0.1524)
				(type default)
			)
			(layer "F.SilkS")
		)
		(fp_line
			(start 1.016 -2.2352)
			(end 1.016 2.2352)
			(stroke
				(width 0.1524)
				(type default)
			)
			(layer "F.SilkS")
		)
		(fp_rect
			(start -1.0922 2.3114)
			(end 1.0922 -2.3114)
			(stroke
				(width 0)
				(type default)
			)
			(fill no)
			(layer "F.CrtYd")
		)
		(fp_poly
			(pts
				(xy -1.0922 -2.3114) (xy 1.0922 -2.3114) (xy 1.0922 2.3114) (xy -1.0922 2.3114)
			)
			(stroke
				(width 0)
				(type default)
			)
			(fill no)
			(layer "F.Fab")
		)
		(pad "1" smd rect
			(at 0 -1.397 270)
			(size 1.651 1.27)
			(layers "F.Cu" "F.Mask" "F.Paste")
			(net "P5V_HDD9")
		)
		(pad "2" smd rect
			(at 0 1.397 270)
			(size 1.651 1.27)
			(layers "F.Cu" "F.Mask" "F.Paste")
			(net "5V_PRE_9")
		)
	)
	(footprint ""
		(layer "F.Cu")
		(at 170.200066 -269.999968)
		(property "Reference" ""
			(at 0 0 0)
			(layer "F.SilkS")
			(hide yes)
			(effects
				(font
					(size 1.27 1.27)
				)
			)
		)
		(property "Value" "*"
			(at -6.3373 -0.4572 0)
			(unlocked yes)
			(layer "F.Fab")
			(hide yes)
			(effects
				(font
					(size 1.016 1.016)
					(thickness 0.1524)
				)
			)
		)
		(duplicate_pad_numbers_are_jumpers no)
		(fp_poly
			(pts
				(arc
					(start 5.0673 0)
					(mid -5.0673 0)
					(end 5.0673 0)
				)
			)
			(stroke
				(width 0)
				(type default)
			)
			(fill no)
			(layer "B.CrtYd")
		)
		(fp_poly
			(pts
				(arc
					(start 5.0673 0)
					(mid -5.0673 0)
					(end 5.0673 0)
				)
			)
			(stroke
				(width 0)
				(type default)
			)
			(fill no)
			(layer "F.CrtYd")
		)
		(fp_poly
			(pts
				(arc
					(start 5.0673 0)
					(mid -5.0673 0)
					(end 5.0673 0)
				)
			)
			(stroke
				(width 0)
				(type default)
			)
			(fill no)
			(layer "B.Fab")
		)
		(fp_poly
			(pts
				(arc
					(start 5.0673 0)
					(mid -5.0673 0)
					(end 5.0673 0)
				)
			)
			(stroke
				(width 0)
				(type default)
			)
			(fill no)
			(layer "F.Fab")
		)
		(pad "1" thru_hole circle
			(at 0 0)
			(size 9.525 9.525)
			(drill 3.556)
			(layers "*.Cu" "*.Mask")
			(remove_unused_layers no)
			(net "Net_90")
			(clearance -2.4765)
			(thermal_gap 0.3048)
			(padstack
				(mode front_inner_back)
				(layer "Inner"
					(shape circle)
					(size 3.9624 3.9624)
					(clearance 0.3048)
				)
				(layer "B.Cu"
					(shape circle)
					(size 9.525 9.525)
					(clearance -2.4765)
				)
			)
		)
		(zone
			(layers "F.Cu" "B.Cu" "In1.Cu" "In2.Cu" "In3.Cu" "In4.Cu" "In5.Cu" "In6.Cu"
				"In7.Cu" "In8.Cu" "In9.Cu" "In10.Cu"
			)
			(hatch none 0.5)
			(connect_pads
				(clearance 0)
			)
			(min_thickness 0.25)
			(keepout
				(tracks not_allowed)
				(vias allowed)
				(pads allowed)
				(copperpour not_allowed)
				(footprints allowed)
			)
			(placement
				(enabled no)
				(sheetname "")
			)
			(fill
				(thermal_gap 0.5)
				(thermal_bridge_width 0.5)
				(island_removal_mode 0)
			)
			(polygon
				(pts
					(arc
						(start 174.962566 -269.999968)
						(mid 165.437566 -269.999968)
						(end 174.962566 -269.999968)
					)
				)
			)
		)
	)
	(footprint ""
		(layer "F.Cu")
		(at 323.674994 -9.19988)
		(property "Reference" ""
			(at 0 0 0)
			(layer "F.SilkS")
			(hide yes)
			(effects
				(font
					(size 1.27 1.27)
				)
			)
		)
		(property "Value" "*"
			(at -6.1214 1.4351 0)
			(unlocked yes)
			(layer "F.Fab")
			(hide yes)
			(effects
				(font
					(size 1.016 1.016)
					(thickness 0.1524)
				)
			)
		)
		(duplicate_pad_numbers_are_jumpers no)
		(fp_poly
			(pts
				(arc
					(start 5.0673 0)
					(mid -5.0673 0)
					(end 5.0673 0)
				)
			)
			(stroke
				(width 0)
				(type default)
			)
			(fill no)
			(layer "B.CrtYd")
		)
		(fp_poly
			(pts
				(arc
					(start 5.0673 0)
					(mid -5.0673 0)
					(end 5.0673 0)
				)
			)
			(stroke
				(width 0)
				(type default)
			)
			(fill no)
			(layer "F.CrtYd")
		)
		(fp_poly
			(pts
				(arc
					(start 5.0673 0)
					(mid -5.0673 0)
					(end 5.0673 0)
				)
			)
			(stroke
				(width 0)
				(type default)
			)
			(fill no)
			(layer "B.Fab")
		)
		(fp_poly
			(pts
				(arc
					(start 5.0673 0)
					(mid -5.0673 0)
					(end 5.0673 0)
				)
			)
			(stroke
				(width 0)
				(type default)
			)
			(fill no)
			(layer "F.Fab")
		)
		(pad "1" thru_hole circle
			(at 0 0)
			(size 9.525 9.525)
			(drill 5.715)
			(layers "*.Cu" "*.Mask")
			(remove_unused_layers no)
			(net "Net_108")
			(clearance -1.397)
			(thermal_gap 0.3048)
			(padstack
				(mode front_inner_back)
				(layer "Inner"
					(shape circle)
					(size 6.1214 6.1214)
					(clearance 0.3048)
				)
				(layer "B.Cu"
					(shape circle)
					(size 9.525 9.525)
					(clearance -1.397)
				)
			)
		)
		(zone
			(layers "F.Cu" "B.Cu" "In1.Cu" "In2.Cu" "In3.Cu" "In4.Cu" "In5.Cu" "In6.Cu"
				"In7.Cu" "In8.Cu" "In9.Cu" "In10.Cu"
			)
			(hatch none 0.5)
			(connect_pads
				(clearance 0)
			)
			(min_thickness 0.25)
			(keepout
				(tracks not_allowed)
				(vias allowed)
				(pads allowed)
				(copperpour not_allowed)
				(footprints allowed)
			)
			(placement
				(enabled no)
				(sheetname "")
			)
			(fill
				(thermal_gap 0.5)
				(thermal_bridge_width 0.5)
				(island_removal_mode 0)
			)
			(polygon
				(pts
					(arc
						(start 328.437494 -9.19988)
						(mid 318.912494 -9.19988)
						(end 328.437494 -9.19988)
					)
				)
			)
		)
	)
	(footprint ""
		(layer "F.Cu")
		(at 475.530926 -62.778894 -90)
		(property "Reference" "C495"
			(at 0 0 270)
			(layer "F.SilkS")
			(hide yes)
			(effects
				(font
					(size 1.27 1.27)
				)
			)
		)
		(property "Value" "SC1U16V3KX-5GP"
			(at 0 -2.8194 270)
			(unlocked yes)
			(layer "F.Fab")
			(hide yes)
			(effects
				(font
					(size 1.016 1.016)
					(thickness 0.1524)
				)
			)
		)
		(property "Device Type" "C603H36"
			(at 0 -4.3434 270)
			(unlocked yes)
			(layer "F.Fab")
			(hide yes)
			(effects
				(font
					(size 1.016 1.016)
					(thickness 0.1524)
				)
			)
		)
		(duplicate_pad_numbers_are_jumpers no)
		(fp_line
			(start 0.508 0)
			(end -0.508 0)
			(stroke
				(width 0.2032)
				(type default)
			)
			(layer "F.SilkS")
		)
		(fp_rect
			(start -0.5842 1.3335)
			(end 0.5842 -1.3335)
			(stroke
				(width 0)
				(type default)
			)
			(fill no)
			(layer "F.CrtYd")
		)
		(fp_rect
			(start -0.5842 1.3335)
			(end 0.5842 -1.3335)
			(stroke
				(width 0)
				(type default)
			)
			(fill no)
			(layer "F.Fab")
		)
		(pad "1" smd custom
			(at 0 -0.762 270)
			(size 0.2159 0.2159)
			(layers "F.Cu" "F.Mask" "F.Paste")
			(net "P5V_HDD35")
			(options
				(clearance outline)
				(anchor circle)
			)
			(primitives
				(gr_poly
					(pts
						(arc
							(start -0.3302 -0.4318)
							(mid -0.402042 -0.402042)
							(end -0.4318 -0.3302)
						)
						(arc
							(start -0.4318 0.3302)
							(mid -0.402042 0.402042)
							(end -0.3302 0.4318)
						)
						(arc
							(start 0.3302 0.4318)
							(mid 0.402042 0.402042)
							(end 0.4318 0.3302)
						)
						(arc
							(start 0.4318 -0.3302)
							(mid 0.402042 -0.402042)
							(end 0.3302 -0.4318)
						)
					)
					(width 0)
					(fill yes)
				)
			)
		)
		(pad "2" smd custom
			(at 0 0.762 270)
			(size 0.2159 0.2159)
			(layers "F.Cu" "F.Mask" "F.Paste")
			(net "GND")
			(options
				(clearance outline)
				(anchor circle)
			)
			(primitives
				(gr_poly
					(pts
						(arc
							(start -0.3302 -0.4318)
							(mid -0.402042 -0.402042)
							(end -0.4318 -0.3302)
						)
						(arc
							(start -0.4318 0.3302)
							(mid -0.402042 0.402042)
							(end -0.3302 0.4318)
						)
						(arc
							(start 0.3302 0.4318)
							(mid 0.402042 0.402042)
							(end 0.4318 0.3302)
						)
						(arc
							(start 0.4318 -0.3302)
							(mid 0.402042 -0.402042)
							(end 0.3302 -0.4318)
						)
					)
					(width 0)
					(fill yes)
				)
			)
		)
	)
	(footprint ""
		(layer "F.Cu")
		(at 219.928948 -21.844 -90)
		(property "Reference" "C32"
			(at 0 0 270)
			(layer "F.SilkS")
			(hide yes)
			(effects
				(font
					(size 1.27 1.27)
				)
			)
		)
		(property "Value" "SC22U25V6KX-2-GP-U"
			(at -2.860802 -5.279644 270)
			(unlocked yes)
			(layer "F.Fab")
			(hide yes)
			(effects
				(font
					(size 1.016 1.016)
					(thickness 0.1524)
				)
			)
		)
		(property "Device Type" "C1206-TO0D3H75"
			(at -2.860802 -6.803644 270)
			(unlocked yes)
			(layer "F.Fab")
			(hide yes)
			(effects
				(font
					(size 1.016 1.016)
					(thickness 0.1524)
				)
			)
		)
		(duplicate_pad_numbers_are_jumpers no)
		(fp_line
			(start -1.3081 2.3749)
			(end -1.3081 -2.3749)
			(stroke
				(width 0.1524)
				(type default)
			)
			(layer "F.SilkS")
		)
		(fp_line
			(start 1.3081 2.3749)
			(end -1.3081 2.3749)
			(stroke
				(width 0.1524)
				(type default)
			)
			(layer "F.SilkS")
		)
		(fp_line
			(start -1.3081 -2.3749)
			(end 1.3081 -2.3749)
			(stroke
				(width 0.1524)
				(type default)
			)
			(layer "F.SilkS")
		)
		(fp_line
			(start 1.3081 -2.3749)
			(end 1.3081 2.3749)
			(stroke
				(width 0.1524)
				(type default)
			)
			(layer "F.SilkS")
		)
		(fp_rect
			(start -0.8001 1.6002)
			(end 0.8001 -1.6002)
			(stroke
				(width 0)
				(type default)
			)
			(fill no)
			(layer "F.CrtYd")
		)
		(fp_poly
			(pts
				(xy -1.5621 2.4511) (xy -1.5621 1.6002) (xy 0.8001 1.6002) (xy 0.8001 -1.6002) (xy -0.8001 -1.6002)
				(xy -0.8001 1.5875) (xy -1.5621 1.5875) (xy -1.5621 -2.4511) (xy 1.5621 -2.4511) (xy 1.5621 2.4511)
			)
			(stroke
				(width 0)
				(type default)
			)
			(fill no)
			(layer "F.CrtYd")
		)
		(fp_rect
			(start -1.5621 2.4511)
			(end 1.5621 -2.4511)
			(stroke
				(width 0)
				(type default)
			)
			(fill no)
			(layer "F.Fab")
		)
		(pad "1" smd rect
			(at 0 -1.392936 270)
			(size 2.1082 1.4478)
			(layers "F.Cu" "F.Mask" "F.Paste")
			(net "P12V_A_COMP")
		)
		(pad "2" smd rect
			(at 0 1.392936 270)
			(size 2.1082 1.4478)
			(layers "F.Cu" "F.Mask" "F.Paste")
			(net "GND")
		)
	)
)
